(kicad_pcb
	(version 20260206)
	(generator "pcbnew")
	(generator_version "10.0")
	(general
		(thickness 1.6)
		(legacy_teardrops no)
	)
	(paper "A4")
	(title_block
		(title "Bryce Canyon_IOM_IOC_16318-2_OCP.brd")
		(comment 1 "Bryce Canyon / footprints 250-258 of 1605")
	)
	(layers
		(0 "F.Cu" signal "TOP")
		(4 "In1.Cu" signal "L2GND")
		(6 "In2.Cu" signal "L3")
		(8 "In3.Cu" signal "L4VCC")
		(10 "In4.Cu" signal "L5VCC")
		(12 "In5.Cu" signal "L6")
		(14 "In6.Cu" signal "L7GND")
		(2 "B.Cu" signal "BOTTOM")
		(9 "F.Adhes" user "F.Adhesive")
		(11 "B.Adhes" user "B.Adhesive")
		(13 "F.Paste" user "Package Geometry/Pastemask Top")
		(15 "B.Paste" user "Package Geometry/Pastemask Bottom")
		(5 "F.SilkS" user "Ref Des/Silkscreen Top")
		(7 "B.SilkS" user "Ref Des/Silkscreen Bottom")
		(1 "F.Mask" user "Board Geometry/Soldermask Top")
		(3 "B.Mask" user "Board Geometry/Soldermask Bottom")
		(17 "Dwgs.User" user "User.Drawings")
		(19 "Cmts.User" user "User.Comments")
		(21 "Eco1.User" user "User.Eco1")
		(23 "Eco2.User" user "User.Eco2")
		(25 "Edge.Cuts" user "Board Geometry/Outline")
		(27 "Margin" user)
		(31 "F.CrtYd" user "Package Geometry/Place Bound Top")
		(29 "B.CrtYd" user "Package Geometry/Place Bound Bottom")
		(35 "F.Fab" user "Ref Des/Assembly Top")
		(33 "B.Fab" user "Ref Des/Assembly Bottom")
	)
	(footprint ""
		(layer "F.Cu")
		(at 182.340504 -151.975566 -90)
		(property "Reference" "R463"
			(at 0 0 270)
			(layer "F.SilkS")
			(hide yes)
			(effects
				(font
					(size 1.27 1.27)
				)
			)
		)
		(property "Value" "10KR2F-2-GP"
			(at 0.064008 -3.993896 270)
			(unlocked yes)
			(layer "F.Fab")
			(hide yes)
			(effects
				(font
					(size 1.016 1.016)
					(thickness 0.1524)
				)
			)
		)
		(property "Device Type" "R402H16"
			(at 0.064008 -5.517896 270)
			(unlocked yes)
			(layer "F.Fab")
			(hide yes)
			(effects
				(font
					(size 1.016 1.016)
					(thickness 0.1524)
				)
			)
		)
		(duplicate_pad_numbers_are_jumpers no)
		(fp_line
			(start -0.508 -0.9398)
			(end -0.508 0.9398)
			(stroke
				(width 0.1524)
				(type default)
			)
			(layer "F.SilkS")
		)
		(fp_line
			(start 0.508 -0.9398)
			(end -0.508 -0.9398)
			(stroke
				(width 0.1524)
				(type default)
			)
			(layer "F.SilkS")
		)
		(fp_rect
			(start -0.508 0.9398)
			(end 0.508 -0.9398)
			(stroke
				(width 0)
				(type default)
			)
			(fill no)
			(layer "F.CrtYd")
		)
		(fp_rect
			(start -0.508 0.9398)
			(end 0.508 -0.9398)
			(stroke
				(width 0)
				(type default)
			)
			(fill no)
			(layer "F.Fab")
		)
		(pad "1" smd custom
			(at 0 -0.4445 270)
			(size 0.1397 0.1397)
			(layers "F.Cu" "F.Mask" "F.Paste")
			(net "P12V_STBY")
			(options
				(clearance outline)
				(anchor circle)
			)
			(primitives
				(gr_poly
					(pts
						(arc
							(start -0.1778 -0.2794)
							(mid -0.249642 -0.249642)
							(end -0.2794 -0.1778)
						)
						(arc
							(start -0.2794 0.1778)
							(mid -0.249642 0.249642)
							(end -0.1778 0.2794)
						)
						(arc
							(start 0.1778 0.2794)
							(mid 0.249642 0.249642)
							(end 0.2794 0.1778)
						)
						(arc
							(start 0.2794 -0.1778)
							(mid 0.249642 -0.249642)
							(end 0.1778 -0.2794)
						)
					)
					(width 0)
					(fill yes)
				)
			)
		)
		(pad "2" smd custom
			(at 0 0.4445 270)
			(size 0.1397 0.1397)
			(layers "F.Cu" "F.Mask" "F.Paste")
			(net "P5V_EN_R")
			(options
				(clearance outline)
				(anchor circle)
			)
			(primitives
				(gr_poly
					(pts
						(arc
							(start -0.1778 -0.2794)
							(mid -0.249642 -0.249642)
							(end -0.2794 -0.1778)
						)
						(arc
							(start -0.2794 0.1778)
							(mid -0.249642 0.249642)
							(end -0.1778 0.2794)
						)
						(arc
							(start 0.1778 0.2794)
							(mid 0.249642 0.249642)
							(end 0.2794 0.1778)
						)
						(arc
							(start 0.2794 -0.1778)
							(mid 0.249642 -0.249642)
							(end 0.1778 -0.2794)
						)
					)
					(width 0)
					(fill yes)
				)
			)
		)
	)
	(footprint ""
		(layer "F.Cu")
		(at 61.974222 -135.331708 -90)
		(property "Reference" "R352"
			(at 0 0 270)
			(layer "F.SilkS")
			(hide yes)
			(effects
				(font
					(size 1.27 1.27)
				)
			)
		)
		(property "Value" "4K7R2F-GP"
			(at 0.064008 -3.993896 270)
			(unlocked yes)
			(layer "F.Fab")
			(hide yes)
			(effects
				(font
					(size 1.016 1.016)
					(thickness 0.1524)
				)
			)
		)
		(property "Device Type" "R402H16"
			(at 0.064008 -5.517896 270)
			(unlocked yes)
			(layer "F.Fab")
			(hide yes)
			(effects
				(font
					(size 1.016 1.016)
					(thickness 0.1524)
				)
			)
		)
		(duplicate_pad_numbers_are_jumpers no)
		(fp_line
			(start -0.508 -0.9398)
			(end -0.508 0.9398)
			(stroke
				(width 0.1524)
				(type default)
			)
			(layer "F.SilkS")
		)
		(fp_line
			(start 0.508 -0.9398)
			(end -0.508 -0.9398)
			(stroke
				(width 0.1524)
				(type default)
			)
			(layer "F.SilkS")
		)
		(fp_rect
			(start -0.508 0.9398)
			(end 0.508 -0.9398)
			(stroke
				(width 0)
				(type default)
			)
			(fill no)
			(layer "F.CrtYd")
		)
		(fp_rect
			(start -0.508 0.9398)
			(end 0.508 -0.9398)
			(stroke
				(width 0)
				(type default)
			)
			(fill no)
			(layer "F.Fab")
		)
		(pad "1" smd custom
			(at 0 -0.4445 270)
			(size 0.1397 0.1397)
			(layers "F.Cu" "F.Mask" "F.Paste")
			(net "P3V3_STBY")
			(options
				(clearance outline)
				(anchor circle)
			)
			(primitives
				(gr_poly
					(pts
						(arc
							(start -0.1778 -0.2794)
							(mid -0.249642 -0.249642)
							(end -0.2794 -0.1778)
						)
						(arc
							(start -0.2794 0.1778)
							(mid -0.249642 0.249642)
							(end -0.1778 0.2794)
						)
						(arc
							(start 0.1778 0.2794)
							(mid 0.249642 0.249642)
							(end 0.2794 0.1778)
						)
						(arc
							(start 0.2794 -0.1778)
							(mid 0.249642 -0.249642)
							(end 0.1778 -0.2794)
						)
					)
					(width 0)
					(fill yes)
				)
			)
		)
		(pad "2" smd custom
			(at 0 0.4445 270)
			(size 0.1397 0.1397)
			(layers "F.Cu" "F.Mask" "F.Paste")
			(net "SLOTID_0")
			(options
				(clearance outline)
				(anchor circle)
			)
			(primitives
				(gr_poly
					(pts
						(arc
							(start -0.1778 -0.2794)
							(mid -0.249642 -0.249642)
							(end -0.2794 -0.1778)
						)
						(arc
							(start -0.2794 0.1778)
							(mid -0.249642 0.249642)
							(end -0.1778 0.2794)
						)
						(arc
							(start 0.1778 0.2794)
							(mid 0.249642 0.249642)
							(end 0.2794 0.1778)
						)
						(arc
							(start 0.2794 -0.1778)
							(mid 0.249642 -0.249642)
							(end 0.1778 -0.2794)
						)
					)
					(width 0)
					(fill yes)
				)
			)
		)
	)
	(footprint ""
		(layer "F.Cu")
		(at 84.983828 -72.525636 90)
		(property "Reference" "VIA9"
			(at 0 0 90)
			(layer "F.SilkS")
			(hide yes)
			(effects
				(font
					(size 1.27 1.27)
				)
			)
		)
		(property "Value" "85OHM-8L-1D6MM-L16L18-GP"
			(at 4.064 0.6096 90)
			(unlocked yes)
			(layer "F.Fab")
			(hide yes)
			(effects
				(font
					(size 1.016 1.016)
					(thickness 0.1524)
				)
			)
		)
		(property "Device Type" "VIA-PCIE-4P-368076"
			(at 4.064 -0.9144 90)
			(unlocked yes)
			(layer "F.Fab")
			(hide yes)
			(effects
				(font
					(size 1.016 1.016)
					(thickness 0.1524)
				)
			)
		)
		(duplicate_pad_numbers_are_jumpers no)
		(fp_rect
			(start -1.8415 0.381)
			(end 1.8415 -0.381)
			(stroke
				(width 0)
				(type default)
			)
			(fill no)
			(layer "F.CrtYd")
		)
		(fp_rect
			(start -1.8415 0.381)
			(end 1.8415 -0.381)
			(stroke
				(width 0)
				(type default)
			)
			(fill no)
			(layer "F.Fab")
		)
		(pad "1" thru_hole circle
			(at -1.4605 0 90)
			(size 0.508 0.508)
			(drill 0.254)
			(layers "*.Cu" "*.Mask")
			(remove_unused_layers no)
			(net "GND")
			(clearance 0.127)
			(thermal_gap 0.127)
		)
		(pad "2" thru_hole circle
			(at -0.4445 0 90)
			(size 0.508 0.508)
			(drill 0.254)
			(layers "*.Cu" "*.Mask")
			(remove_unused_layers no)
			(net "PCIE_IOM_TO_COMP_16_DP")
			(clearance 0.127)
			(thermal_gap 0.127)
		)
		(pad "3" thru_hole circle
			(at 0.4445 0 90)
			(size 0.508 0.508)
			(drill 0.254)
			(layers "*.Cu" "*.Mask")
			(remove_unused_layers no)
			(net "PCIE_IOM_TO_COMP_16_DN")
			(clearance 0.127)
			(thermal_gap 0.127)
		)
		(pad "4" thru_hole circle
			(at 1.4605 0 90)
			(size 0.508 0.508)
			(drill 0.254)
			(layers "*.Cu" "*.Mask")
			(remove_unused_layers no)
			(net "GND")
			(clearance 0.127)
			(thermal_gap 0.127)
		)
	)
	(footprint ""
		(layer "F.Cu")
		(at 202.164188 -133.250432)
		(property "Reference" "R547"
			(at 0 0 0)
			(layer "F.SilkS")
			(hide yes)
			(effects
				(font
					(size 1.27 1.27)
				)
			)
		)
		(property "Value" "0R2J-2-GP"
			(at 0.064008 -3.993896 0)
			(unlocked yes)
			(layer "F.Fab")
			(hide yes)
			(effects
				(font
					(size 1.016 1.016)
					(thickness 0.1524)
				)
			)
		)
		(property "Device Type" "R402H16"
			(at 0.064008 -5.517896 0)
			(unlocked yes)
			(layer "F.Fab")
			(hide yes)
			(effects
				(font
					(size 1.016 1.016)
					(thickness 0.1524)
				)
			)
		)
		(duplicate_pad_numbers_are_jumpers no)
		(fp_line
			(start -0.508 -0.9398)
			(end -0.508 0.9398)
			(stroke
				(width 0.1524)
				(type default)
			)
			(layer "F.SilkS")
		)
		(fp_line
			(start 0.508 -0.9398)
			(end -0.508 -0.9398)
			(stroke
				(width 0.1524)
				(type default)
			)
			(layer "F.SilkS")
		)
		(fp_rect
			(start -0.508 0.9398)
			(end 0.508 -0.9398)
			(stroke
				(width 0)
				(type default)
			)
			(fill no)
			(layer "F.CrtYd")
		)
		(fp_rect
			(start -0.508 0.9398)
			(end 0.508 -0.9398)
			(stroke
				(width 0)
				(type default)
			)
			(fill no)
			(layer "F.Fab")
		)
		(pad "1" smd custom
			(at 0 -0.4445)
			(size 0.1397 0.1397)
			(layers "F.Cu" "F.Mask" "F.Paste")
			(net "P5V_STBY")
			(options
				(clearance outline)
				(anchor circle)
			)
			(primitives
				(gr_poly
					(pts
						(arc
							(start -0.1778 -0.2794)
							(mid -0.249642 -0.249642)
							(end -0.2794 -0.1778)
						)
						(arc
							(start -0.2794 0.1778)
							(mid -0.249642 0.249642)
							(end -0.1778 0.2794)
						)
						(arc
							(start 0.1778 0.2794)
							(mid 0.249642 0.249642)
							(end 0.2794 0.1778)
						)
						(arc
							(start 0.2794 -0.1778)
							(mid 0.249642 -0.249642)
							(end 0.1778 -0.2794)
						)
					)
					(width 0)
					(fill yes)
				)
			)
		)
		(pad "2" smd custom
			(at 0 0.4445)
			(size 0.1397 0.1397)
			(layers "F.Cu" "F.Mask" "F.Paste")
			(net "TPS74801_1V5_BIAS")
			(options
				(clearance outline)
				(anchor circle)
			)
			(primitives
				(gr_poly
					(pts
						(arc
							(start -0.1778 -0.2794)
							(mid -0.249642 -0.249642)
							(end -0.2794 -0.1778)
						)
						(arc
							(start -0.2794 0.1778)
							(mid -0.249642 0.249642)
							(end -0.1778 0.2794)
						)
						(arc
							(start 0.1778 0.2794)
							(mid 0.249642 0.249642)
							(end 0.2794 0.1778)
						)
						(arc
							(start 0.2794 -0.1778)
							(mid 0.249642 -0.249642)
							(end 0.1778 -0.2794)
						)
					)
					(width 0)
					(fill yes)
				)
			)
		)
	)
	(footprint ""
		(layer "F.Cu")
		(at 164.6174 -128.0414 90)
		(property "Reference" "R519"
			(at 0 0 90)
			(layer "F.SilkS")
			(hide yes)
			(effects
				(font
					(size 1.27 1.27)
				)
			)
		)
		(property "Value" "1KR2F-3-GP"
			(at 0.064008 -3.993896 90)
			(unlocked yes)
			(layer "F.Fab")
			(hide yes)
			(effects
				(font
					(size 1.016 1.016)
					(thickness 0.1524)
				)
			)
		)
		(property "Device Type" "R402H16"
			(at 0.064008 -5.517896 90)
			(unlocked yes)
			(layer "F.Fab")
			(hide yes)
			(effects
				(font
					(size 1.016 1.016)
					(thickness 0.1524)
				)
			)
		)
		(duplicate_pad_numbers_are_jumpers no)
		(fp_line
			(start 0.508 -0.9398)
			(end -0.508 -0.9398)
			(stroke
				(width 0.1524)
				(type default)
			)
			(layer "F.SilkS")
		)
		(fp_line
			(start -0.508 -0.9398)
			(end -0.508 0.9398)
			(stroke
				(width 0.1524)
				(type default)
			)
			(layer "F.SilkS")
		)
		(fp_rect
			(start -0.508 0.9398)
			(end 0.508 -0.9398)
			(stroke
				(width 0)
				(type default)
			)
			(fill no)
			(layer "F.CrtYd")
		)
		(fp_rect
			(start -0.508 0.9398)
			(end 0.508 -0.9398)
			(stroke
				(width 0)
				(type default)
			)
			(fill no)
			(layer "F.Fab")
		)
		(pad "1" smd custom
			(at 0 -0.4445 90)
			(size 0.1397 0.1397)
			(layers "F.Cu" "F.Mask" "F.Paste")
			(net "P1V8_STBY_SW")
			(options
				(clearance outline)
				(anchor circle)
			)
			(primitives
				(gr_poly
					(pts
						(arc
							(start -0.1778 -0.2794)
							(mid -0.249642 -0.249642)
							(end -0.2794 -0.1778)
						)
						(arc
							(start -0.2794 0.1778)
							(mid -0.249642 0.249642)
							(end -0.1778 0.2794)
						)
						(arc
							(start 0.1778 0.2794)
							(mid 0.249642 0.249642)
							(end 0.2794 0.1778)
						)
						(arc
							(start 0.2794 -0.1778)
							(mid 0.249642 -0.249642)
							(end 0.1778 -0.2794)
						)
					)
					(width 0)
					(fill yes)
				)
			)
		)
		(pad "2" smd custom
			(at 0 0.4445 90)
			(size 0.1397 0.1397)
			(layers "F.Cu" "F.Mask" "F.Paste")
			(net "P1V8_STBY_VFB_R")
			(options
				(clearance outline)
				(anchor circle)
			)
			(primitives
				(gr_poly
					(pts
						(arc
							(start -0.1778 -0.2794)
							(mid -0.249642 -0.249642)
							(end -0.2794 -0.1778)
						)
						(arc
							(start -0.2794 0.1778)
							(mid -0.249642 0.249642)
							(end -0.1778 0.2794)
						)
						(arc
							(start 0.1778 0.2794)
							(mid 0.249642 0.249642)
							(end 0.2794 0.1778)
						)
						(arc
							(start 0.2794 -0.1778)
							(mid 0.249642 -0.249642)
							(end 0.1778 -0.2794)
						)
					)
					(width 0)
					(fill yes)
				)
			)
		)
	)
	(footprint ""
		(layer "F.Cu")
		(at 195.6562 -49.9618)
		(property "Reference" "TP143"
			(at 0 0 0)
			(layer "F.SilkS")
			(hide yes)
			(effects
				(font
					(size 1.27 1.27)
				)
			)
		)
		(property "Value" "TPAD28-2-GP"
			(at -0.0127 -1.6637 0)
			(unlocked yes)
			(layer "F.Fab")
			(hide yes)
			(effects
				(font
					(size 1.016 1.016)
					(thickness 0.1524)
				)
			)
		)
		(property "Device Type" "TPAD28"
			(at -0.0127 -3.1877 0)
			(unlocked yes)
			(layer "F.Fab")
			(hide yes)
			(effects
				(font
					(size 1.016 1.016)
					(thickness 0.1524)
				)
			)
		)
		(duplicate_pad_numbers_are_jumpers no)
		(fp_poly
			(pts
				(arc
					(start 0.3556 0)
					(mid -0.3556 0)
					(end 0.3556 0)
				)
			)
			(stroke
				(width 0)
				(type default)
			)
			(fill no)
			(layer "F.CrtYd")
		)
		(fp_poly
			(pts
				(arc
					(start 0.6096 0)
					(mid -0.6096 0)
					(end 0.6096 0)
				)
			)
			(stroke
				(width 0)
				(type default)
			)
			(fill no)
			(layer "F.Fab")
		)
		(pad "1" smd circle
			(at 0 0)
			(size 0.7112 0.7112)
			(layers "F.Cu" "F.Mask" "F.Paste")
			(net "ICE1_TDO")
		)
	)
	(footprint ""
		(layer "F.Cu")
		(at 27.800046 -186.56681 180)
		(property "Reference" "C176"
			(at 0 0 180)
			(layer "F.SilkS")
			(hide yes)
			(effects
				(font
					(size 1.27 1.27)
				)
			)
		)
		(property "Value" "SC10U16V5KX-7-GP-U"
			(at -0.0762 -6.1214 180)
			(unlocked yes)
			(layer "F.Fab")
			(hide yes)
			(effects
				(font
					(size 1.016 1.016)
					(thickness 0.1524)
				)
			)
		)
		(property "Device Type" "C805H58"
			(at -0.0762 -8.1534 180)
			(unlocked yes)
			(layer "F.Fab")
			(hide yes)
			(effects
				(font
					(size 1.016 1.016)
					(thickness 0.1524)
				)
			)
		)
		(duplicate_pad_numbers_are_jumpers no)
		(fp_line
			(start 0.635 0)
			(end -0.635 0)
			(stroke
				(width 0.508)
				(type default)
			)
			(layer "F.SilkS")
		)
		(fp_rect
			(start -0.9652 1.778)
			(end 0.9652 -1.778)
			(stroke
				(width 0)
				(type default)
			)
			(fill no)
			(layer "F.CrtYd")
		)
		(fp_poly
			(pts
				(xy -0.9652 -1.778) (xy 0.9652 -1.778) (xy 0.9652 1.778) (xy -0.9652 1.778)
			)
			(stroke
				(width 0)
				(type default)
			)
			(fill no)
			(layer "F.Fab")
		)
		(pad "1" smd rect
			(at 0 -0.9652 180)
			(size 1.397 1.143)
			(layers "F.Cu" "F.Mask" "F.Paste")
			(net "P12V_STBY_VIN_PU2")
		)
		(pad "2" smd rect
			(at 0 0.9652 180)
			(size 1.397 1.143)
			(layers "F.Cu" "F.Mask" "F.Paste")
			(net "GND")
		)
	)
	(footprint ""
		(layer "F.Cu")
		(at 82.441796 -173.57598 90)
		(property "Reference" "C194"
			(at 0 0 90)
			(layer "F.SilkS")
			(hide yes)
			(effects
				(font
					(size 1.27 1.27)
				)
			)
		)
		(property "Value" "SC10U6D3V5KX-4GP"
			(at -0.0762 -6.1214 90)
			(unlocked yes)
			(layer "F.Fab")
			(hide yes)
			(effects
				(font
					(size 1.016 1.016)
					(thickness 0.1524)
				)
			)
		)
		(property "Device Type" "C805H58"
			(at -0.0762 -8.1534 90)
			(unlocked yes)
			(layer "F.Fab")
			(hide yes)
			(effects
				(font
					(size 1.016 1.016)
					(thickness 0.1524)
				)
			)
		)
		(duplicate_pad_numbers_are_jumpers no)
		(fp_line
			(start 0.635 0)
			(end -0.635 0)
			(stroke
				(width 0.508)
				(type default)
			)
			(layer "F.SilkS")
		)
		(fp_rect
			(start -0.9652 1.778)
			(end 0.9652 -1.778)
			(stroke
				(width 0)
				(type default)
			)
			(fill no)
			(layer "F.CrtYd")
		)
		(fp_poly
			(pts
				(xy -0.9652 -1.778) (xy 0.9652 -1.778) (xy 0.9652 1.778) (xy -0.9652 1.778)
			)
			(stroke
				(width 0)
				(type default)
			)
			(fill no)
			(layer "F.Fab")
		)
		(pad "1" smd rect
			(at 0 -0.9652 90)
			(size 1.397 1.143)
			(layers "F.Cu" "F.Mask" "F.Paste")
			(net "TPS74801_P2V5_STBY_OUT")
		)
		(pad "2" smd rect
			(at 0 0.9652 90)
			(size 1.397 1.143)
			(layers "F.Cu" "F.Mask" "F.Paste")
			(net "GND")
		)
	)
	(footprint ""
		(layer "F.Cu")
		(at 180.594 -157.226 90)
		(property "Reference" "C160"
			(at 0 0 90)
			(layer "F.SilkS")
			(hide yes)
			(effects
				(font
					(size 1.27 1.27)
				)
			)
		)
		(property "Value" "SCD1U50V3KX-GP"
			(at 0 -2.8194 90)
			(unlocked yes)
			(layer "F.Fab")
			(hide yes)
			(effects
				(font
					(size 1.016 1.016)
					(thickness 0.1524)
				)
			)
		)
		(property "Device Type" "C603H36"
			(at 0 -4.3434 90)
			(unlocked yes)
			(layer "F.Fab")
			(hide yes)
			(effects
				(font
					(size 1.016 1.016)
					(thickness 0.1524)
				)
			)
		)
		(duplicate_pad_numbers_are_jumpers no)
		(fp_line
			(start 0.508 0)
			(end -0.508 0)
			(stroke
				(width 0.2032)
				(type default)
			)
			(layer "F.SilkS")
		)
		(fp_rect
			(start -0.5842 1.3335)
			(end 0.5842 -1.3335)
			(stroke
				(width 0)
				(type default)
			)
			(fill no)
			(layer "F.CrtYd")
		)
		(fp_rect
			(start -0.5842 1.3335)
			(end 0.5842 -1.3335)
			(stroke
				(width 0)
				(type default)
			)
			(fill no)
			(layer "F.Fab")
		)
		(pad "1" smd custom
			(at 0 -0.762 90)
			(size 0.2159 0.2159)
			(layers "F.Cu" "F.Mask" "F.Paste")
			(net "P5V_STBY")
			(options
				(clearance outline)
				(anchor circle)
			)
			(primitives
				(gr_poly
					(pts
						(arc
							(start -0.3302 -0.4318)
							(mid -0.402042 -0.402042)
							(end -0.4318 -0.3302)
						)
						(arc
							(start -0.4318 0.3302)
							(mid -0.402042 0.402042)
							(end -0.3302 0.4318)
						)
						(arc
							(start 0.3302 0.4318)
							(mid 0.402042 0.402042)
							(end 0.4318 0.3302)
						)
						(arc
							(start 0.4318 -0.3302)
							(mid 0.402042 -0.402042)
							(end 0.3302 -0.4318)
						)
					)
					(width 0)
					(fill yes)
				)
			)
		)
		(pad "2" smd custom
			(at 0 0.762 90)
			(size 0.2159 0.2159)
			(layers "F.Cu" "F.Mask" "F.Paste")
			(net "P5V_LL_R")
			(options
				(clearance outline)
				(anchor circle)
			)
			(primitives
				(gr_poly
					(pts
						(arc
							(start -0.3302 -0.4318)
							(mid -0.402042 -0.402042)
							(end -0.4318 -0.3302)
						)
						(arc
							(start -0.4318 0.3302)
							(mid -0.402042 0.402042)
							(end -0.3302 0.4318)
						)
						(arc
							(start 0.3302 0.4318)
							(mid 0.402042 0.402042)
							(end 0.4318 0.3302)
						)
						(arc
							(start 0.4318 -0.3302)
							(mid 0.402042 -0.402042)
							(end 0.3302 -0.4318)
						)
					)
					(width 0)
					(fill yes)
				)
			)
		)
	)
)
